(kicad_pcb
	(version 20240108)
	(generator "pcbnew")
	(generator_version "8.0")
	(general
		(thickness 1.62)
		(legacy_teardrops no)
	)
	(paper "A4")
	(title_block
		(title "Jetson Orin Baseboard")
		(date "2025-03-12")
		(rev "1.3.4")
		(company "Antmicro Ltd")
		(comment 1 "www.antmicro.com")
		(comment 9 "footprints 99-103 of 677")
	)
	(layers
		(0 "F.Cu" signal)
		(1 "In1.Cu" signal)
		(2 "In2.Cu" signal)
		(3 "In3.Cu" signal)
		(4 "In4.Cu" jumper)
		(5 "In5.Cu" signal)
		(6 "In6.Cu" signal)
		(31 "B.Cu" signal)
		(32 "B.Adhes" user "B.Adhesive")
		(33 "F.Adhes" user "F.Adhesive")
		(34 "B.Paste" user)
		(35 "F.Paste" user)
		(36 "B.SilkS" user "B.Silkscreen")
		(37 "F.SilkS" user "F.Silkscreen")
		(38 "B.Mask" user)
		(39 "F.Mask" user)
		(40 "Dwgs.User" user "User.Drawings")
		(41 "Cmts.User" user "User.Comments")
		(42 "Eco1.User" user "User.Eco1")
		(43 "Eco2.User" user "User.Eco2")
		(44 "Edge.Cuts" user)
		(45 "Margin" user)
		(46 "B.CrtYd" user "B.Courtyard")
		(47 "F.CrtYd" user "F.Courtyard")
		(48 "B.Fab" user)
		(49 "F.Fab" user)
	)
	(footprint "antmicro-footprints:R_0402_1005Metric"
		(layer "F.Cu")
		(at 92.8 92.2)
		(descr "Resistor SMD 0402")
		(tags "resistor SMD 0402")
		(property "Reference" "R228"
			(at 0 -0.7 0)
			(layer "F.SilkS")
			(effects
				(font
					(size 0.7 0.7)
					(thickness 0.15)
				)
				(justify left bottom)
			)
		)
		(property "Value" "R_10k_0402"
			(at 0 1.4 0)
			(layer "F.Fab")
			(effects
				(font
					(size 0.7 0.7)
					(thickness 0.15)
				)
				(justify left bottom)
			)
		)
		(property "Footprint" "antmicro-footprints:R_0402_1005Metric"
			(at 0 0 0)
			(layer "F.Fab")
			(hide yes)
			(effects
				(font
					(size 1.27 1.27)
					(thickness 0.15)
				)
			)
		)
		(property "Datasheet" "https://www.bourns.com/docs/product-datasheets/cr.pdf"
			(at 0 0 0)
			(layer "F.Fab")
			(hide yes)
			(effects
				(font
					(size 1.27 1.27)
					(thickness 0.15)
				)
			)
		)
		(property "Author" "Antmicro"
			(at 0 0 0)
			(layer "F.Fab")
			(hide yes)
			(effects
				(font
					(size 1 1)
					(thickness 0.15)
				)
			)
		)
		(property "License" "Apache-2.0"
			(at 0 0 0)
			(layer "F.Fab")
			(hide yes)
			(effects
				(font
					(size 1 1)
					(thickness 0.15)
				)
			)
		)
		(property "MPN" "CR0402-FX-1002GLF"
			(at 0 0 0)
			(layer "F.Fab")
			(hide yes)
			(effects
				(font
					(size 1 1)
					(thickness 0.15)
				)
			)
		)
		(property "Manufacturer" "Bourns"
			(at 0 0 0)
			(layer "F.Fab")
			(hide yes)
			(effects
				(font
					(size 1 1)
					(thickness 0.15)
				)
			)
		)
		(property "Tolerance" "1%"
			(at 0 0 0)
			(layer "F.Fab")
			(hide yes)
			(effects
				(font
					(size 1 1)
					(thickness 0.15)
				)
			)
		)
		(property "Val" "10k"
			(at 0 0 0)
			(layer "F.Fab")
			(hide yes)
			(effects
				(font
					(size 1 1)
					(thickness 0.15)
				)
			)
		)
		(sheetname "HDMI")
		(sheetfile "hdmi.kicad_sch")
		(attr smd exclude_from_pos_files exclude_from_bom dnp)
		(fp_rect
			(start -0.925 -0.47)
			(end 0.925 0.47)
			(stroke
				(width 0.05)
				(type default)
			)
			(fill none)
			(layer "F.CrtYd")
		)
		(fp_rect
			(start -0.5 -0.25)
			(end 0.5 0.25)
			(stroke
				(width 0.15)
				(type solid)
			)
			(fill none)
			(layer "F.Fab")
		)
		(fp_text user "${REFERENCE}"
			(at -0.95 3.168 0)
			(layer "F.Fab")
			(hide yes)
			(effects
				(font
					(size 0.7 0.7)
					(thickness 0.15)
				)
				(justify left bottom)
			)
		)
		(fp_text user "License: Apache-2.0"
			(at -0.95 5.169 0)
			(layer "F.Fab")
			(hide yes)
			(effects
				(font
					(size 0.7 0.7)
					(thickness 0.15)
				)
				(justify left bottom)
			)
		)
		(fp_text user "Author: Antmicro"
			(at -0.95 4.169 0)
			(layer "F.Fab")
			(hide yes)
			(effects
				(font
					(size 0.7 0.7)
					(thickness 0.15)
				)
				(justify left bottom)
			)
		)
		(pad "1" smd roundrect
			(at -0.48 0)
			(size 0.59 0.64)
			(layers "F.Cu" "F.Paste" "F.Mask")
			(roundrect_rratio 0.25)
			(net 624 "Net-(Q3-D)")
			(pintype "passive")
		)
		(pad "2" smd roundrect
			(at 0.48 0)
			(size 0.59 0.64)
			(layers "F.Cu" "F.Paste" "F.Mask")
			(roundrect_rratio 0.25)
			(net 87 "+3V3")
			(pintype "passive")
		)
	)
	(footprint "antmicro-footprints:SW_KMR211NGLFS_SMD"
		(layer "F.Cu")
		(at 128.9 125.9 180)
		(property "Reference" "S3"
			(at 2.41 1.97 180)
			(layer "F.SilkS")
			(effects
				(font
					(size 0.7 0.7)
					(thickness 0.15)
				)
				(justify left bottom)
			)
		)
		(property "Value" "SW_KMR211NGLFS_SMD"
			(at -3 3 180)
			(layer "F.Fab")
			(effects
				(font
					(size 0.7 0.7)
					(thickness 0.15)
				)
				(justify left bottom)
			)
		)
		(property "Footprint" "antmicro-footprints:SW_KMR211NGLFS_SMD"
			(at 0 0 180)
			(layer "F.Fab")
			(hide yes)
			(effects
				(font
					(size 1.27 1.27)
					(thickness 0.15)
				)
			)
		)
		(property "Datasheet" "http://www.farnell.com/datasheets/2631211.pdf"
			(at 0 0 180)
			(layer "F.Fab")
			(hide yes)
			(effects
				(font
					(size 1.27 1.27)
					(thickness 0.15)
				)
			)
		)
		(property "Author" "Antmicro"
			(at 257.8 251.8 0)
			(layer "F.Fab")
			(hide yes)
			(effects
				(font
					(size 1 1)
					(thickness 0.15)
				)
			)
		)
		(property "License" "Apache-2.0"
			(at 257.8 251.8 0)
			(layer "F.Fab")
			(hide yes)
			(effects
				(font
					(size 1 1)
					(thickness 0.15)
				)
			)
		)
		(property "MPN" "KMR211NGLFS"
			(at 257.8 251.8 0)
			(layer "F.Fab")
			(hide yes)
			(effects
				(font
					(size 1 1)
					(thickness 0.15)
				)
			)
		)
		(property "Manufacturer" "C&K"
			(at 257.8 251.8 0)
			(layer "F.Fab")
			(hide yes)
			(effects
				(font
					(size 1 1)
					(thickness 0.15)
				)
			)
		)
		(sheetname "Peripherals")
		(sheetfile "peripherals.kicad_sch")
		(attr smd)
		(fp_line
			(start 2.101 1.601)
			(end 2.101 1.48)
			(stroke
				(width 0.15)
				(type solid)
			)
			(layer "F.SilkS")
		)
		(fp_line
			(start 2.101 1.601)
			(end -2.1 1.601)
			(stroke
				(width 0.15)
				(type solid)
			)
			(layer "F.SilkS")
		)
		(fp_line
			(start 2.101 -1.58)
			(end 2.101 -1.459)
			(stroke
				(width 0.15)
				(type solid)
			)
			(layer "F.SilkS")
		)
		(fp_line
			(start 2.101 -1.6)
			(end -2.1 -1.6)
			(stroke
				(width 0.15)
				(type solid)
			)
			(layer "F.SilkS")
		)
		(fp_line
			(start -2.1 1.601)
			(end -2.1 1.48)
			(stroke
				(width 0.15)
				(type solid)
			)
			(layer "F.SilkS")
		)
		(fp_line
			(start -2.1 -1.6)
			(end -2.1 -1.499)
			(stroke
				(width 0.15)
				(type solid)
			)
			(layer "F.SilkS")
		)
		(fp_rect
			(start 2.751 1.75)
			(end -2.748 -1.749)
			(stroke
				(width 0.05)
				(type solid)
			)
			(fill none)
			(layer "F.CrtYd")
		)
		(fp_line
			(start 2.101 1.601)
			(end 2.101 -1.6)
			(stroke
				(width 0.15)
				(type solid)
			)
			(layer "F.Fab")
		)
		(fp_line
			(start 2.101 -1.6)
			(end -2.1 -1.6)
			(stroke
				(width 0.15)
				(type solid)
			)
			(layer "F.Fab")
		)
		(fp_line
			(start 0.25 0.802)
			(end -0.248 0.802)
			(stroke
				(width 0.15)
				(type solid)
			)
			(layer "F.Fab")
		)
		(fp_line
			(start -0.248 -0.8)
			(end 0.25 -0.8)
			(stroke
				(width 0.15)
				(type solid)
			)
			(layer "F.Fab")
		)
		(fp_line
			(start -2.1 1.601)
			(end 2.101 1.601)
			(stroke
				(width 0.15)
				(type solid)
			)
			(layer "F.Fab")
		)
		(fp_line
			(start -2.1 -1.6)
			(end -2.1 1.601)
			(stroke
				(width 0.15)
				(type solid)
			)
			(layer "F.Fab")
		)
		(fp_arc
			(start 0.25 -0.8)
			(mid 1.051001 0.001)
			(end 0.25 0.802)
			(stroke
				(width 0.15)
				(type solid)
			)
			(layer "F.Fab")
		)
		(fp_arc
			(start -0.248 0.802)
			(mid -1.050001 0.001)
			(end -0.248 -0.8)
			(stroke
				(width 0.15)
				(type solid)
			)
			(layer "F.Fab")
		)
		(fp_text user "License: Apache-2.0"
			(at -3 6.75 180)
			(layer "F.Fab")
			(hide yes)
			(effects
				(font
					(size 0.7 0.7)
					(thickness 0.15)
				)
				(justify left bottom)
			)
		)
		(fp_text user "${REFERENCE}"
			(at -3 4.25 180)
			(layer "F.Fab")
			(hide yes)
			(effects
				(font
					(size 0.7 0.7)
					(thickness 0.15)
				)
				(justify left bottom)
			)
		)
		(fp_text user "Author: Antmicro"
			(at -3 5.5 180)
			(layer "F.Fab")
			(hide yes)
			(effects
				(font
					(size 0.7 0.7)
					(thickness 0.15)
				)
				(justify left bottom)
			)
		)
		(pad "1" smd rect
			(at -2.048 -0.8)
			(size 0.9 1)
			(layers "F.Cu" "F.Paste" "F.Mask")
			(net 46 "USER_BTN1")
			(pinfunction "1")
			(pintype "passive")
		)
		(pad "2" smd rect
			(at 2.05 -0.8)
			(size 0.9 1)
			(layers "F.Cu" "F.Paste" "F.Mask")
			(net 46 "USER_BTN1")
			(pinfunction "2")
			(pintype "passive")
		)
		(pad "3" smd rect
			(at -2.048 0.802)
			(size 0.9 1)
			(layers "F.Cu" "F.Paste" "F.Mask")
			(net 1 "GND")
			(pinfunction "3")
			(pintype "passive")
		)
		(pad "4" smd rect
			(at 2.05 0.802)
			(size 0.9 1)
			(layers "F.Cu" "F.Paste" "F.Mask")
			(net 1 "GND")
			(pinfunction "4")
			(pintype "passive")
		)
	)
	(footprint "antmicro-footprints:TP_SMD_0.75mm"
		(layer "F.Cu")
		(at 127.905 113.22 180)
		(property "Reference" "TP8"
			(at -0.42 -0.425 180)
			(layer "F.SilkS")
			(effects
				(font
					(size 0.7 0.7)
					(thickness 0.15)
				)
				(justify left bottom)
			)
		)
		(property "Value" "TP_0.75mm_SMD"
			(at 0 1.2 180)
			(layer "F.Fab")
			(effects
				(font
					(size 0.7 0.7)
					(thickness 0.15)
				)
				(justify left bottom)
			)
		)
		(property "Footprint" "antmicro-footprints:TP_SMD_0.75mm"
			(at 0 0 180)
			(layer "F.Fab")
			(hide yes)
			(effects
				(font
					(size 1.27 1.27)
					(thickness 0.15)
				)
			)
		)
		(property "Author" "Antmicro"
			(at 255.81 226.44 0)
			(layer "F.Fab")
			(hide yes)
			(effects
				(font
					(size 1 1)
					(thickness 0.15)
				)
			)
		)
		(property "License" "Apache-2.0"
			(at 255.81 226.44 0)
			(layer "F.Fab")
			(hide yes)
			(effects
				(font
					(size 1 1)
					(thickness 0.15)
				)
			)
		)
		(property "MPN" ""
			(at 255.81 226.44 0)
			(layer "F.Fab")
			(hide yes)
			(effects
				(font
					(size 1 1)
					(thickness 0.15)
				)
			)
		)
		(property "Manufacturer" ""
			(at 255.81 226.44 0)
			(layer "F.Fab")
			(hide yes)
			(effects
				(font
					(size 1 1)
					(thickness 0.15)
				)
			)
		)
		(sheetname "M.2")
		(sheetfile "m-2.kicad_sch")
		(attr exclude_from_pos_files exclude_from_bom)
		(fp_circle
			(center 0 0)
			(end 0.475 0)
			(stroke
				(width 0.05)
				(type default)
			)
			(fill none)
			(layer "F.CrtYd")
		)
		(fp_text user "Author: Antmicro"
			(at -0.4 3.901 180)
			(layer "F.Fab")
			(hide yes)
			(effects
				(font
					(size 0.7 0.7)
					(thickness 0.15)
				)
				(justify left bottom)
			)
		)
		(fp_text user "${REFERENCE}"
			(at -0.4 2.7 180)
			(layer "F.Fab")
			(hide yes)
			(effects
				(font
					(size 0.7 0.7)
					(thickness 0.15)
				)
				(justify left bottom)
			)
		)
		(fp_text user "License: Apache-2.0"
			(at -0.4 5.101 180)
			(layer "F.Fab")
			(hide yes)
			(effects
				(font
					(size 0.7 0.7)
					(thickness 0.15)
				)
				(justify left bottom)
			)
		)
		(pad "1" smd circle
			(at 0 0 180)
			(size 0.75 0.75)
			(layers "F.Cu" "F.Mask")
			(net 218 "/M.2/M2_E_W_DIS_2")
			(pinfunction "1")
			(pintype "passive")
		)
	)
	(footprint "antmicro-footprints:R_0402_1005Metric"
		(layer "F.Cu")
		(at 78.17 85.88 -90)
		(descr "Resistor SMD 0402")
		(tags "resistor SMD 0402")
		(property "Reference" "R264"
			(at -3.56 -0.46 90)
			(layer "F.SilkS")
			(effects
				(font
					(size 0.7 0.7)
					(thickness 0.15)
				)
				(justify right bottom)
			)
		)
		(property "Value" "R_0R_0402"
			(at -1.011843 1.772047 90)
			(layer "F.Fab")
			(effects
				(font
					(size 0.7 0.7)
					(thickness 0.15)
				)
				(justify right bottom)
			)
		)
		(property "Footprint" "antmicro-footprints:R_0402_1005Metric"
			(at 0 0 -90)
			(layer "F.Fab")
			(hide yes)
			(effects
				(font
					(size 1.27 1.27)
					(thickness 0.15)
				)
			)
		)
		(property "Datasheet" "https://industrial.panasonic.com/cdbs/www-data/pdf/RDA0000/AOA0000C301.pdf"
			(at 0 0 -90)
			(layer "F.Fab")
			(hide yes)
			(effects
				(font
					(size 1.27 1.27)
					(thickness 0.15)
				)
			)
		)
		(property "Author" "Antmicro"
			(at -7.71 164.05 0)
			(layer "F.Fab")
			(hide yes)
			(effects
				(font
					(size 1 1)
					(thickness 0.15)
				)
			)
		)
		(property "Current" "1A"
			(at -7.71 164.05 0)
			(layer "F.Fab")
			(hide yes)
			(effects
				(font
					(size 1 1)
					(thickness 0.15)
				)
			)
		)
		(property "License" "Apache-2.0"
			(at -7.71 164.05 0)
			(layer "F.Fab")
			(hide yes)
			(effects
				(font
					(size 1 1)
					(thickness 0.15)
				)
			)
		)
		(property "MPN" "ERJ2GE0R00X"
			(at -7.71 164.05 0)
			(layer "F.Fab")
			(hide yes)
			(effects
				(font
					(size 1 1)
					(thickness 0.15)
				)
			)
		)
		(property "Manufacturer" "Panasonic"
			(at -7.71 164.05 0)
			(layer "F.Fab")
			(hide yes)
			(effects
				(font
					(size 1 1)
					(thickness 0.15)
				)
			)
		)
		(property "Tolerance" ""
			(at -7.71 164.05 0)
			(layer "F.Fab")
			(hide yes)
			(effects
				(font
					(size 1 1)
					(thickness 0.15)
				)
			)
		)
		(property "Val" "0R"
			(at -7.71 164.05 0)
			(layer "F.Fab")
			(hide yes)
			(effects
				(font
					(size 1 1)
					(thickness 0.15)
				)
			)
		)
		(sheetname "Supply")
		(sheetfile "supply.kicad_sch")
		(attr smd)
		(fp_rect
			(start -0.925 -0.47)
			(end 0.925 0.47)
			(stroke
				(width 0.05)
				(type default)
			)
			(fill none)
			(layer "F.CrtYd")
		)
		(fp_rect
			(start -0.5 -0.25)
			(end 0.5 0.25)
			(stroke
				(width 0.15)
				(type solid)
			)
			(fill none)
			(layer "F.Fab")
		)
		(fp_text user "License: Apache-2.0"
			(at -0.95 5.169 90)
			(layer "F.Fab")
			(hide yes)
			(effects
				(font
					(size 0.7 0.7)
					(thickness 0.15)
				)
				(justify right bottom)
			)
		)
		(fp_text user "${REFERENCE}"
			(at -0.95 3.168 90)
			(layer "F.Fab")
			(hide yes)
			(effects
				(font
					(size 0.7 0.7)
					(thickness 0.15)
				)
				(justify right bottom)
			)
		)
		(fp_text user "Author: Antmicro"
			(at -0.95 4.169 90)
			(layer "F.Fab")
			(hide yes)
			(effects
				(font
					(size 0.7 0.7)
					(thickness 0.15)
				)
				(justify right bottom)
			)
		)
		(pad "1" smd roundrect
			(at -0.48 0 270)
			(size 0.59 0.64)
			(layers "F.Cu" "F.Paste" "F.Mask")
			(roundrect_rratio 0.25)
			(net 86 "~{RESET}")
			(pintype "passive")
		)
		(pad "2" smd roundrect
			(at 0.48 0 270)
			(size 0.59 0.64)
			(layers "F.Cu" "F.Paste" "F.Mask")
			(roundrect_rratio 0.25)
			(net 771 "/Supply/3V3_EN")
			(pintype "passive")
		)
	)
	(footprint "antmicro-footprints:R_0402_1005Metric"
		(layer "F.Cu")
		(at 60.15 106.55 -90)
		(descr "Resistor SMD 0402")
		(tags "resistor SMD 0402")
		(property "Reference" "R144"
			(at -0.75 -0.4 -90)
			(layer "F.SilkS")
			(effects
				(font
					(size 0.7 0.7)
					(thickness 0.15)
				)
				(justify left bottom)
			)
		)
		(property "Value" "R_0R_0402"
			(at 0 1.4 -90)
			(layer "F.Fab")
			(effects
				(font
					(size 0.7 0.7)
					(thickness 0.15)
				)
				(justify left bottom)
			)
		)
		(property "Footprint" "antmicro-footprints:R_0402_1005Metric"
			(at 0 0 -90)
			(layer "F.Fab")
			(hide yes)
			(effects
				(font
					(size 1.27 1.27)
					(thickness 0.15)
				)
			)
		)
		(property "Datasheet" "https://industrial.panasonic.com/cdbs/www-data/pdf/RDA0000/AOA0000C301.pdf"
			(at 0 0 -90)
			(layer "F.Fab")
			(hide yes)
			(effects
				(font
					(size 1.27 1.27)
					(thickness 0.15)
				)
			)
		)
		(property "Author" "Antmicro"
			(at -46.4 166.7 0)
			(layer "F.Fab")
			(hide yes)
			(effects
				(font
					(size 1 1)
					(thickness 0.15)
				)
			)
		)
		(property "Current" "1A"
			(at -46.4 166.7 0)
			(layer "F.Fab")
			(hide yes)
			(effects
				(font
					(size 1 1)
					(thickness 0.15)
				)
			)
		)
		(property "License" "Apache-2.0"
			(at -46.4 166.7 0)
			(layer "F.Fab")
			(hide yes)
			(effects
				(font
					(size 1 1)
					(thickness 0.15)
				)
			)
		)
		(property "MPN" "ERJ2GE0R00X"
			(at -46.4 166.7 0)
			(layer "F.Fab")
			(hide yes)
			(effects
				(font
					(size 1 1)
					(thickness 0.15)
				)
			)
		)
		(property "Manufacturer" "Panasonic"
			(at -46.4 166.7 0)
			(layer "F.Fab")
			(hide yes)
			(effects
				(font
					(size 1 1)
					(thickness 0.15)
				)
			)
		)
		(property "Tolerance" ""
			(at -46.4 166.7 0)
			(layer "F.Fab")
			(hide yes)
			(effects
				(font
					(size 1 1)
					(thickness 0.15)
				)
			)
		)
		(property "Val" "0R"
			(at -46.4 166.7 0)
			(layer "F.Fab")
			(hide yes)
			(effects
				(font
					(size 1 1)
					(thickness 0.15)
				)
			)
		)
		(sheetname "USB Debug, DP")
		(sheetfile "usb.kicad_sch")
		(attr smd exclude_from_pos_files exclude_from_bom dnp)
		(fp_rect
			(start -0.925 -0.47)
			(end 0.925 0.47)
			(stroke
				(width 0.05)
				(type default)
			)
			(fill none)
			(layer "F.CrtYd")
		)
		(fp_rect
			(start -0.5 -0.25)
			(end 0.5 0.25)
			(stroke
				(width 0.15)
				(type solid)
			)
			(fill none)
			(layer "F.Fab")
		)
		(fp_text user "${REFERENCE}"
			(at -0.95 3.168 -90)
			(layer "F.Fab")
			(hide yes)
			(effects
				(font
					(size 0.7 0.7)
					(thickness 0.15)
				)
				(justify left bottom)
			)
		)
		(fp_text user "License: Apache-2.0"
			(at -0.95 5.169 -90)
			(layer "F.Fab")
			(hide yes)
			(effects
				(font
					(size 0.7 0.7)
					(thickness 0.15)
				)
				(justify left bottom)
			)
		)
		(fp_text user "Author: Antmicro"
			(at -0.95 4.169 -90)
			(layer "F.Fab")
			(hide yes)
			(effects
				(font
					(size 0.7 0.7)
					(thickness 0.15)
				)
				(justify left bottom)
			)
		)
		(pad "1" smd roundrect
			(at -0.48 0 270)
			(size 0.59 0.64)
			(layers "F.Cu" "F.Paste" "F.Mask")
			(roundrect_rratio 0.25)
			(net 549 "/USB Debug, DP/USBC3_5V_PEN")
			(pintype "passive")
		)
		(pad "2" smd roundrect
			(at 0.48 0 270)
			(size 0.59 0.64)
			(layers "F.Cu" "F.Paste" "F.Mask")
			(roundrect_rratio 0.25)
			(net 99 "+5V")
			(pintype "passive")
		)
	)
)
